FILE_TYPE = MACRO_DRAWING;
SET COLOR_WIRE YELLOW;
SET COLOR_PROP ORANGE;
SET COLOR_DOT WHITE;
SET COLOR_ARC YELLOW;
SET COLOR_BODY GREEN;
SET COLOR_NOTE PURPLE;
SET PROP_DISPLAY VALUE;
SET PAGE_NUMBER P187;
FORCEADD UNIVERSAL_GND..1
(-2125 200);
FORCEPROP 3 LASTPIN (-2125 250) SIG_NAME GND\g
J 0
(-2115 260);
DISPLAY 0.659574 (-2115 260);
PAINT MONO (-2115 260);
DISPLAY INVISIBLE (-2115 260);
FORCEPROP 2 LAST CDS_LIB logical_power
J 0
(-2125 200);
PAINT MONO (-2125 200);
DISPLAY INVISIBLE (-2125 200);
FORCEPROP 1 LAST HDL_POWER GND
J 1
(-2100 125);
DISPLAY 0.872340 (-2100 125);
PAINT GREEN (-2100 125);
DISPLAY INVISIBLE (-2100 125);
FORCEPROP 1 LAST PATH I11
J 0
(-2050 200);
DISPLAY 0.872340 (-2050 200);
PAINT AQUA (-2050 200);
DISPLAY INVISIBLE (-2050 200);
FORCEPROP 2 LAST ROOM IO_SLOT
J 1
(-2350 275);
DISPLAY 0.744681 (-2350 275);
DISPLAY INVISIBLE (-2350 275);
FORCEADD UNIVERSAL_POWER..1
(-2125 -875);
FORCEPROP 3 LASTPIN (-2125 -925) SIG_NAME P3V3_AUX\g
J 0
(-2115 -915);
DISPLAY 0.659574 (-2115 -915);
PAINT MONO (-2115 -915);
DISPLAY INVISIBLE (-2115 -915);
FORCEPROP 1 LAST HDL_POWER P3V3_AUX
J 1
(-2125 -825);
DISPLAY 0.872340 (-2125 -825);
PAINT GREEN (-2125 -825);
FORCEPROP 2 LAST CDS_LIB logical_power
J 0
(-2125 -875);
PAINT MONO (-2125 -875);
DISPLAY INVISIBLE (-2125 -875);
FORCEPROP 1 LAST PATH I12
J 0
(-2075 -850);
DISPLAY 0.872340 (-2075 -850);
PAINT AQUA (-2075 -850);
DISPLAY INVISIBLE (-2075 -850);
FORCEADD Q_RES..2
(-2125 -1125);
FORCEPROP 1 LAST PART_NUMBER CS21002FB06
J 0
(-2085 -1250);
DISPLAY 0.638298 (-2085 -1250);
DISPLAY INVISIBLE (-2085 -1250);
FORCEPROP 1 LAST VALUE 1K
J 0
(-2080 -1050);
DISPLAY 0.787234 (-2080 -1050);
FORCEPROP 1 LAST WATTAGE 1/16W
J 0
(-2085 -1150);
DISPLAY 0.787234 (-2085 -1150);
FORCEPROP 1 LAST PACK_TYPE 0402LF
J 0
(-2085 -1300);
DISPLAY 0.787234 (-2085 -1300);
FORCEPROP 1 LAST MATERIAL EMPTY
J 0
(-2085 -1200);
DISPLAY 0.787234 (-2085 -1200);
FORCEPROP 1 LAST TOLERANCE 1%
J 0
(-2080 -1100);
DISPLAY 0.787234 (-2080 -1100);
FORCEPROP 1 LAST $LOCATION R623
J 0
(-2080 -1000);
DISPLAY 0.978723 (-2080 -1000);
FORCEPROP 1 LASTPIN (-2125 -1025) $PN 1
J 0
(-2120 -1063);
DISPLAY 0.787234 (-2120 -1063);
FORCEPROP 1 LASTPIN (-2125 -1225) $PN 2
J 0
(-2120 -1215);
DISPLAY 0.787234 (-2120 -1215);
FORCEPROP 2 LAST CDS_LIB pure_quanta
J 0
(-2125 -1125);
PAINT MONO (-2125 -1125);
DISPLAY INVISIBLE (-2125 -1125);
FORCEPROP 1 LAST PATH I13
J 0
(-2075 -950);
DISPLAY 0.978723 (-2075 -950);
PAINT WHITE (-2075 -950);
DISPLAY INVISIBLE (-2075 -950);
FORCEPROP 2 LAST CDS_LOCATION R623
J 0
(-2075 -900);
DISPLAY 1.021277 (-2075 -900);
DISPLAY INVISIBLE (-2075 -900);
FORCEPROP 2 LAST $SEC 1
J 0
(-2075 -900);
DISPLAY 0.680851 (-2075 -900);
PAINT MONO (-2075 -900);
DISPLAY INVISIBLE (-2075 -900);
FORCEPROP 2 LAST CDS_SEC 1
J 0
(-2075 -900);
DISPLAY 1.021277 (-2075 -900);
DISPLAY INVISIBLE (-2075 -900);
FORCEADD Q_RES..2
(-2125 -1650);
FORCEPROP 1 LAST PART_NUMBER CS31002FB08
J 0
(-2085 -1775);
DISPLAY 0.787234 (-2085 -1775);
DISPLAY INVISIBLE (-2085 -1775);
FORCEPROP 1 LAST VALUE 10K
J 0
(-2080 -1575);
DISPLAY 0.787234 (-2080 -1575);
FORCEPROP 1 LAST PACK_TYPE 0402LF
J 0
(-2085 -1825);
DISPLAY 0.787234 (-2085 -1825);
FORCEPROP 1 LAST MATERIAL CHIP
J 0
(-2085 -1725);
DISPLAY 0.787234 (-2085 -1725);
FORCEPROP 1 LAST WATTAGE 1/16W
J 0
(-2085 -1675);
DISPLAY 0.787234 (-2085 -1675);
FORCEPROP 1 LAST TOLERANCE 1%
J 0
(-2080 -1625);
DISPLAY 0.787234 (-2080 -1625);
FORCEPROP 1 LAST $LOCATION R624
J 0
(-2080 -1525);
DISPLAY 0.978723 (-2080 -1525);
FORCEPROP 1 LASTPIN (-2125 -1550) $PN 1
J 0
(-2120 -1588);
DISPLAY 0.787234 (-2120 -1588);
FORCEPROP 1 LASTPIN (-2125 -1750) $PN 2
J 0
(-2120 -1740);
DISPLAY 0.787234 (-2120 -1740);
FORCEPROP 2 LAST CDS_LIB pure_quanta
J 0
(-2125 -1650);
PAINT MONO (-2125 -1650);
DISPLAY INVISIBLE (-2125 -1650);
FORCEPROP 1 LAST PATH I14
J 0
(-2075 -1475);
DISPLAY 0.978723 (-2075 -1475);
PAINT WHITE (-2075 -1475);
DISPLAY INVISIBLE (-2075 -1475);
FORCEPROP 2 LAST CDS_LOCATION R624
J 0
(-2075 -1425);
DISPLAY 1.021277 (-2075 -1425);
DISPLAY INVISIBLE (-2075 -1425);
FORCEPROP 2 LAST $SEC 1
J 0
(-2075 -1425);
DISPLAY 0.680851 (-2075 -1425);
PAINT MONO (-2075 -1425);
DISPLAY INVISIBLE (-2075 -1425);
FORCEPROP 2 LAST CDS_SEC 1
J 0
(-2075 -1425);
DISPLAY 1.021277 (-2075 -1425);
DISPLAY INVISIBLE (-2075 -1425);
FORCEADD UNIVERSAL_GND..1
(-2125 -1875);
FORCEPROP 3 LASTPIN (-2125 -1825) SIG_NAME GND\g
J 0
(-2115 -1815);
DISPLAY 0.659574 (-2115 -1815);
PAINT MONO (-2115 -1815);
DISPLAY INVISIBLE (-2115 -1815);
FORCEPROP 2 LAST CDS_LIB logical_power
J 0
(-2125 -1875);
PAINT MONO (-2125 -1875);
DISPLAY INVISIBLE (-2125 -1875);
FORCEPROP 1 LAST HDL_POWER GND
J 1
(-2100 -1950);
DISPLAY 0.872340 (-2100 -1950);
PAINT GREEN (-2100 -1950);
DISPLAY INVISIBLE (-2100 -1950);
FORCEPROP 1 LAST PATH I15
J 0
(-2050 -1875);
DISPLAY 0.872340 (-2050 -1875);
PAINT AQUA (-2050 -1875);
DISPLAY INVISIBLE (-2050 -1875);
FORCEPROP 2 LAST ROOM IO_SLOT
J 1
(-2350 -1800);
DISPLAY 0.744681 (-2350 -1800);
DISPLAY INVISIBLE (-2350 -1800);
FORCEADD OFFPAGE..2
(-4050 2650);
FORCEPROP 2 LAST $XR0 185 
J 0
(-3861 2650);
DISPLAY 0.638298 (-3861 2650);
PAINT MONO (-3861 2650);
FORCEPROP 2 LAST CDS_LIB standard
J 0
(-4050 2650);
PAINT MONO (-4050 2650);
DISPLAY INVISIBLE (-4050 2650);
FORCEPROP 1 LAST OFFPAGE TRUE
J 0
(-3725 2525);
DISPLAY 0.872340 (-3725 2525);
DISPLAY INVISIBLE (-3725 2525);
FORCEPROP 1 LAST COMMENT_BODY TRUE
J 0
(-4095 2555);
DISPLAY 0.872340 (-4095 2555);
PAINT GREEN (-4095 2555);
DISPLAY INVISIBLE (-4095 2555);
FORCEPROP 2 LAST PATH I16
J 0
(-3875 2725);
DISPLAY 1.021277 (-3875 2725);
DISPLAY INVISIBLE (-3875 2725);
FORCEADD UNIVERSAL_POWER..1
(-5300 3200);
FORCEPROP 3 LASTPIN (-5300 3150) SIG_NAME P3V3_AUX\g
J 0
(-5290 3160);
DISPLAY 0.659574 (-5290 3160);
PAINT MONO (-5290 3160);
DISPLAY INVISIBLE (-5290 3160);
FORCEPROP 1 LAST HDL_POWER P3V3_AUX
J 1
(-5300 3250);
DISPLAY 0.872340 (-5300 3250);
PAINT GREEN (-5300 3250);
FORCEPROP 2 LAST CDS_LIB logical_power
J 0
(-5300 3200);
PAINT MONO (-5300 3200);
DISPLAY INVISIBLE (-5300 3200);
FORCEPROP 1 LAST PATH I17
J 0
(-5250 3225);
DISPLAY 0.872340 (-5250 3225);
PAINT AQUA (-5250 3225);
DISPLAY INVISIBLE (-5250 3225);
FORCEADD Q_RES..2
(-5300 2950);
FORCEPROP 1 LAST PART_NUMBER CS31002FB08
J 0
(-5260 2825);
DISPLAY 0.787234 (-5260 2825);
DISPLAY INVISIBLE (-5260 2825);
FORCEPROP 1 LAST VALUE 10K
J 0
(-5255 3025);
DISPLAY 0.787234 (-5255 3025);
FORCEPROP 1 LAST TOLERANCE 1%
J 0
(-5255 2975);
DISPLAY 0.787234 (-5255 2975);
FORCEPROP 1 LAST PACK_TYPE 0402LF
J 0
(-5260 2775);
DISPLAY 0.787234 (-5260 2775);
FORCEPROP 1 LAST WATTAGE 1/16W
J 0
(-5260 2925);
DISPLAY 0.787234 (-5260 2925);
FORCEPROP 1 LAST MATERIAL CHIP
J 0
(-5260 2875);
DISPLAY 0.787234 (-5260 2875);
FORCEPROP 1 LAST $LOCATION R613
J 0
(-5255 3075);
DISPLAY 0.978723 (-5255 3075);
FORCEPROP 1 LASTPIN (-5300 3050) $PN 1
J 0
(-5295 3012);
DISPLAY 0.787234 (-5295 3012);
FORCEPROP 1 LASTPIN (-5300 2850) $PN 2
J 0
(-5295 2860);
DISPLAY 0.787234 (-5295 2860);
FORCEPROP 2 LAST CDS_LIB pure_quanta
J 0
(-5300 2950);
PAINT MONO (-5300 2950);
DISPLAY INVISIBLE (-5300 2950);
FORCEPROP 1 LAST PATH I18
J 0
(-5250 3125);
DISPLAY 0.978723 (-5250 3125);
PAINT WHITE (-5250 3125);
DISPLAY INVISIBLE (-5250 3125);
FORCEPROP 2 LAST CDS_LOCATION R613
J 0
(-5250 3175);
DISPLAY 1.021277 (-5250 3175);
DISPLAY INVISIBLE (-5250 3175);
FORCEPROP 2 LAST $SEC 1
J 0
(-5250 3175);
DISPLAY 0.680851 (-5250 3175);
PAINT MONO (-5250 3175);
DISPLAY INVISIBLE (-5250 3175);
FORCEPROP 2 LAST CDS_SEC 1
J 0
(-5250 3175);
DISPLAY 1.021277 (-5250 3175);
DISPLAY INVISIBLE (-5250 3175);
FORCEADD OFFPAGE..2
(-7175 2650);
FORCEPROP 2 LAST $XR0 183 
J 0
(-6986 2650);
DISPLAY 0.638298 (-6986 2650);
PAINT MONO (-6986 2650);
FORCEPROP 2 LAST CDS_LIB standard
J 0
(-7175 2650);
PAINT MONO (-7175 2650);
DISPLAY INVISIBLE (-7175 2650);
FORCEPROP 1 LAST OFFPAGE TRUE
J 0
(-6850 2525);
DISPLAY 0.872340 (-6850 2525);
DISPLAY INVISIBLE (-6850 2525);
FORCEPROP 1 LAST COMMENT_BODY TRUE
J 0
(-7220 2555);
DISPLAY 0.872340 (-7220 2555);
PAINT GREEN (-7220 2555);
DISPLAY INVISIBLE (-7220 2555);
FORCEPROP 2 LAST PATH I19
J 0
(-7000 2725);
DISPLAY 1.021277 (-7000 2725);
DISPLAY INVISIBLE (-7000 2725);
FORCEADD UNIVERSAL_POWER..1
(-8425 3200);
FORCEPROP 3 LASTPIN (-8425 3150) SIG_NAME P3V3_AUX\g
J 0
(-8415 3160);
DISPLAY 0.659574 (-8415 3160);
PAINT MONO (-8415 3160);
DISPLAY INVISIBLE (-8415 3160);
FORCEPROP 1 LAST HDL_POWER P3V3_AUX
J 1
(-8425 3250);
DISPLAY 0.872340 (-8425 3250);
PAINT GREEN (-8425 3250);
FORCEPROP 2 LAST CDS_LIB logical_power
J 0
(-8425 3200);
PAINT MONO (-8425 3200);
DISPLAY INVISIBLE (-8425 3200);
FORCEPROP 1 LAST PATH I20
J 0
(-8375 3225);
DISPLAY 0.872340 (-8375 3225);
PAINT AQUA (-8375 3225);
DISPLAY INVISIBLE (-8375 3225);
FORCEADD Q_RES..2
(-8425 2950);
FORCEPROP 1 LAST PART_NUMBER CS21002FB06
J 0
(-8385 2825);
DISPLAY 0.638298 (-8385 2825);
DISPLAY INVISIBLE (-8385 2825);
FORCEPROP 1 LAST PACK_TYPE 0402LF
J 0
(-8385 2775);
DISPLAY 0.787234 (-8385 2775);
FORCEPROP 1 LAST MATERIAL EMPTY
J 0
(-8385 2875);
DISPLAY 0.787234 (-8385 2875);
FORCEPROP 1 LAST VALUE 1K
J 0
(-8380 3025);
DISPLAY 0.787234 (-8380 3025);
FORCEPROP 1 LAST WATTAGE 1/16W
J 0
(-8385 2925);
DISPLAY 0.787234 (-8385 2925);
FORCEPROP 1 LAST TOLERANCE 1%
J 0
(-8380 2975);
DISPLAY 0.787234 (-8380 2975);
FORCEPROP 1 LAST $LOCATION R607
J 0
(-8380 3075);
DISPLAY 0.978723 (-8380 3075);
FORCEPROP 1 LASTPIN (-8425 3050) $PN 1
J 0
(-8420 3012);
DISPLAY 0.787234 (-8420 3012);
FORCEPROP 1 LASTPIN (-8425 2850) $PN 2
J 0
(-8420 2860);
DISPLAY 0.787234 (-8420 2860);
FORCEPROP 2 LAST CDS_LIB pure_quanta
J 0
(-8425 2950);
PAINT MONO (-8425 2950);
DISPLAY INVISIBLE (-8425 2950);
FORCEPROP 1 LAST PATH I21
J 0
(-8375 3125);
DISPLAY 0.978723 (-8375 3125);
PAINT WHITE (-8375 3125);
DISPLAY INVISIBLE (-8375 3125);
FORCEPROP 2 LAST CDS_LOCATION R607
J 0
(-8375 3175);
DISPLAY 1.021277 (-8375 3175);
DISPLAY INVISIBLE (-8375 3175);
FORCEPROP 2 LAST $SEC 1
J 0
(-8375 3175);
DISPLAY 0.680851 (-8375 3175);
PAINT MONO (-8375 3175);
DISPLAY INVISIBLE (-8375 3175);
FORCEPROP 2 LAST CDS_SEC 1
J 0
(-8375 3175);
DISPLAY 1.021277 (-8375 3175);
DISPLAY INVISIBLE (-8375 3175);
FORCEADD OFFPAGE..2
(-4050 650);
FORCEPROP 2 LAST $XR0 184 
J 0
(-3861 650);
DISPLAY 0.638298 (-3861 650);
PAINT MONO (-3861 650);
FORCEPROP 2 LAST CDS_LIB standard
J 0
(-4050 650);
PAINT MONO (-4050 650);
DISPLAY INVISIBLE (-4050 650);
FORCEPROP 1 LAST OFFPAGE TRUE
J 0
(-3725 525);
DISPLAY 0.872340 (-3725 525);
DISPLAY INVISIBLE (-3725 525);
FORCEPROP 1 LAST COMMENT_BODY TRUE
J 0
(-4095 555);
DISPLAY 0.872340 (-4095 555);
PAINT GREEN (-4095 555);
DISPLAY INVISIBLE (-4095 555);
FORCEPROP 2 LAST PATH I22
J 0
(-3875 725);
DISPLAY 1.021277 (-3875 725);
DISPLAY INVISIBLE (-3875 725);
FORCEADD Q_RES..2
(-5300 2425);
FORCEPROP 1 LAST PART_NUMBER CS21002FB06
J 0
(-5260 2300);
DISPLAY 0.638298 (-5260 2300);
DISPLAY INVISIBLE (-5260 2300);
FORCEPROP 1 LAST PACK_TYPE 0402LF
J 0
(-5260 2250);
DISPLAY 0.787234 (-5260 2250);
FORCEPROP 1 LAST VALUE 1K
J 0
(-5255 2500);
DISPLAY 0.787234 (-5255 2500);
FORCEPROP 1 LAST WATTAGE 1/16W
J 0
(-5260 2400);
DISPLAY 0.787234 (-5260 2400);
FORCEPROP 1 LAST MATERIAL EMPTY
J 0
(-5260 2350);
DISPLAY 0.787234 (-5260 2350);
FORCEPROP 1 LAST TOLERANCE 1%
J 0
(-5255 2450);
DISPLAY 0.787234 (-5255 2450);
FORCEPROP 1 LAST $LOCATION R614
J 0
(-5255 2550);
DISPLAY 0.978723 (-5255 2550);
FORCEPROP 1 LASTPIN (-5300 2525) $PN 1
J 0
(-5295 2487);
DISPLAY 0.787234 (-5295 2487);
FORCEPROP 1 LASTPIN (-5300 2325) $PN 2
J 0
(-5295 2335);
DISPLAY 0.787234 (-5295 2335);
FORCEPROP 2 LAST CDS_LIB pure_quanta
J 0
(-5300 2425);
PAINT MONO (-5300 2425);
DISPLAY INVISIBLE (-5300 2425);
FORCEPROP 1 LAST PATH I23
J 0
(-5250 2600);
DISPLAY 0.978723 (-5250 2600);
PAINT WHITE (-5250 2600);
DISPLAY INVISIBLE (-5250 2600);
FORCEPROP 2 LAST CDS_LOCATION R614
J 0
(-5250 2650);
DISPLAY 1.021277 (-5250 2650);
DISPLAY INVISIBLE (-5250 2650);
FORCEPROP 2 LAST $SEC 1
J 0
(-5250 2650);
DISPLAY 0.680851 (-5250 2650);
PAINT MONO (-5250 2650);
DISPLAY INVISIBLE (-5250 2650);
FORCEPROP 2 LAST CDS_SEC 1
J 0
(-5250 2650);
DISPLAY 1.021277 (-5250 2650);
DISPLAY INVISIBLE (-5250 2650);
FORCEADD UNIVERSAL_GND..1
(-5300 2200);
FORCEPROP 3 LASTPIN (-5300 2250) SIG_NAME GND\g
J 0
(-5290 2260);
DISPLAY 0.659574 (-5290 2260);
PAINT MONO (-5290 2260);
DISPLAY INVISIBLE (-5290 2260);
FORCEPROP 2 LAST CDS_LIB logical_power
J 0
(-5300 2200);
PAINT MONO (-5300 2200);
DISPLAY INVISIBLE (-5300 2200);
FORCEPROP 1 LAST HDL_POWER GND
J 1
(-5275 2125);
DISPLAY 0.872340 (-5275 2125);
PAINT GREEN (-5275 2125);
DISPLAY INVISIBLE (-5275 2125);
FORCEPROP 1 LAST PATH I24
J 0
(-5225 2200);
DISPLAY 0.872340 (-5225 2200);
PAINT AQUA (-5225 2200);
DISPLAY INVISIBLE (-5225 2200);
FORCEPROP 2 LAST ROOM IO_SLOT
J 1
(-5525 2275);
DISPLAY 0.744681 (-5525 2275);
DISPLAY INVISIBLE (-5525 2275);
FORCEADD UNIVERSAL_POWER..1
(-5300 1200);
FORCEPROP 3 LASTPIN (-5300 1150) SIG_NAME P3V3_AUX\g
J 0
(-5290 1160);
DISPLAY 0.659574 (-5290 1160);
PAINT MONO (-5290 1160);
DISPLAY INVISIBLE (-5290 1160);
FORCEPROP 1 LAST HDL_POWER P3V3_AUX
J 1
(-5300 1250);
DISPLAY 0.872340 (-5300 1250);
PAINT GREEN (-5300 1250);
FORCEPROP 2 LAST CDS_LIB logical_power
J 0
(-5300 1200);
PAINT MONO (-5300 1200);
DISPLAY INVISIBLE (-5300 1200);
FORCEPROP 1 LAST PATH I25
J 0
(-5250 1225);
DISPLAY 0.872340 (-5250 1225);
PAINT AQUA (-5250 1225);
DISPLAY INVISIBLE (-5250 1225);
FORCEADD OFFPAGE..2
(-4050 -1400);
FORCEPROP 2 LAST $XR0 184 
J 0
(-3861 -1400);
DISPLAY 0.638298 (-3861 -1400);
PAINT MONO (-3861 -1400);
FORCEPROP 2 LAST CDS_LIB standard
J 0
(-4050 -1400);
PAINT MONO (-4050 -1400);
DISPLAY INVISIBLE (-4050 -1400);
FORCEPROP 1 LAST OFFPAGE TRUE
J 0
(-3725 -1525);
DISPLAY 0.872340 (-3725 -1525);
DISPLAY INVISIBLE (-3725 -1525);
FORCEPROP 1 LAST COMMENT_BODY TRUE
J 0
(-4095 -1495);
DISPLAY 0.872340 (-4095 -1495);
PAINT GREEN (-4095 -1495);
DISPLAY INVISIBLE (-4095 -1495);
FORCEPROP 2 LAST PATH I27
J 0
(-3875 -1325);
DISPLAY 1.021277 (-3875 -1325);
DISPLAY INVISIBLE (-3875 -1325);
FORCEADD UNIVERSAL_POWER..1
(-5300 -900);
FORCEPROP 3 LASTPIN (-5300 -950) SIG_NAME P3V3_AUX\g
J 0
(-5290 -940);
DISPLAY 0.659574 (-5290 -940);
PAINT MONO (-5290 -940);
DISPLAY INVISIBLE (-5290 -940);
FORCEPROP 1 LAST HDL_POWER P3V3_AUX
J 1
(-5300 -850);
DISPLAY 0.872340 (-5300 -850);
PAINT GREEN (-5300 -850);
FORCEPROP 2 LAST CDS_LIB logical_power
J 0
(-5300 -900);
PAINT MONO (-5300 -900);
DISPLAY INVISIBLE (-5300 -900);
FORCEPROP 1 LAST PATH I30
J 0
(-5250 -875);
DISPLAY 0.872340 (-5250 -875);
PAINT AQUA (-5250 -875);
DISPLAY INVISIBLE (-5250 -875);
FORCEADD OFFPAGE..2
(-7175 650);
FORCEPROP 2 LAST $XR0 185 
J 0
(-6986 650);
DISPLAY 0.638298 (-6986 650);
PAINT MONO (-6986 650);
FORCEPROP 2 LAST CDS_LIB standard
J 0
(-7175 650);
PAINT MONO (-7175 650);
DISPLAY INVISIBLE (-7175 650);
FORCEPROP 1 LAST OFFPAGE TRUE
J 0
(-6850 525);
DISPLAY 0.872340 (-6850 525);
DISPLAY INVISIBLE (-6850 525);
FORCEPROP 1 LAST COMMENT_BODY TRUE
J 0
(-7220 555);
DISPLAY 0.872340 (-7220 555);
PAINT GREEN (-7220 555);
DISPLAY INVISIBLE (-7220 555);
FORCEPROP 2 LAST PATH I32
J 0
(-7000 725);
DISPLAY 1.021277 (-7000 725);
DISPLAY INVISIBLE (-7000 725);
FORCEADD OFFPAGE..2
(-7175 -1400);
FORCEPROP 2 LAST $XR0 184 
J 0
(-6986 -1400);
DISPLAY 0.638298 (-6986 -1400);
PAINT MONO (-6986 -1400);
FORCEPROP 2 LAST CDS_LIB standard
J 0
(-7175 -1400);
PAINT MONO (-7175 -1400);
DISPLAY INVISIBLE (-7175 -1400);
FORCEPROP 1 LAST OFFPAGE TRUE
J 0
(-6850 -1525);
DISPLAY 0.872340 (-6850 -1525);
DISPLAY INVISIBLE (-6850 -1525);
FORCEPROP 1 LAST COMMENT_BODY TRUE
J 0
(-7220 -1495);
DISPLAY 0.872340 (-7220 -1495);
PAINT GREEN (-7220 -1495);
DISPLAY INVISIBLE (-7220 -1495);
FORCEPROP 2 LAST PATH I33
J 0
(-7000 -1325);
DISPLAY 1.021277 (-7000 -1325);
DISPLAY INVISIBLE (-7000 -1325);
FORCEADD UNIVERSAL_GND..1
(-5300 -1850);
FORCEPROP 3 LASTPIN (-5300 -1800) SIG_NAME GND\g
J 0
(-5290 -1790);
DISPLAY 0.659574 (-5290 -1790);
PAINT MONO (-5290 -1790);
DISPLAY INVISIBLE (-5290 -1790);
FORCEPROP 2 LAST CDS_LIB logical_power
J 0
(-5300 -1850);
PAINT MONO (-5300 -1850);
DISPLAY INVISIBLE (-5300 -1850);
FORCEPROP 1 LAST HDL_POWER GND
J 1
(-5275 -1925);
DISPLAY 0.872340 (-5275 -1925);
PAINT GREEN (-5275 -1925);
DISPLAY INVISIBLE (-5275 -1925);
FORCEPROP 1 LAST PATH I35
J 0
(-5225 -1850);
DISPLAY 0.872340 (-5225 -1850);
PAINT AQUA (-5225 -1850);
DISPLAY INVISIBLE (-5225 -1850);
FORCEPROP 2 LAST ROOM IO_SLOT
J 1
(-5525 -1775);
DISPLAY 0.744681 (-5525 -1775);
DISPLAY INVISIBLE (-5525 -1775);
FORCEADD Q_RES..2
(-8425 2425);
FORCEPROP 1 LAST PART_NUMBER CS31002FB08
J 0
(-8385 2300);
DISPLAY 0.787234 (-8385 2300);
DISPLAY INVISIBLE (-8385 2300);
FORCEPROP 1 LAST VALUE 10K
J 0
(-8380 2500);
DISPLAY 0.787234 (-8380 2500);
FORCEPROP 1 LAST MATERIAL CHIP
J 0
(-8385 2350);
DISPLAY 0.787234 (-8385 2350);
FORCEPROP 1 LAST PACK_TYPE 0402LF
J 0
(-8385 2250);
DISPLAY 0.787234 (-8385 2250);
FORCEPROP 1 LAST TOLERANCE 1%
J 0
(-8380 2450);
DISPLAY 0.787234 (-8380 2450);
FORCEPROP 1 LAST WATTAGE 1/16W
J 0
(-8385 2400);
DISPLAY 0.787234 (-8385 2400);
FORCEPROP 1 LAST $LOCATION R608
J 0
(-8380 2550);
DISPLAY 0.978723 (-8380 2550);
FORCEPROP 1 LASTPIN (-8425 2525) $PN 1
J 0
(-8420 2487);
DISPLAY 0.787234 (-8420 2487);
FORCEPROP 1 LASTPIN (-8425 2325) $PN 2
J 0
(-8420 2335);
DISPLAY 0.787234 (-8420 2335);
FORCEPROP 2 LAST CDS_LIB pure_quanta
J 0
(-8425 2425);
PAINT MONO (-8425 2425);
DISPLAY INVISIBLE (-8425 2425);
FORCEPROP 1 LAST PATH I36
J 0
(-8375 2600);
DISPLAY 0.978723 (-8375 2600);
PAINT WHITE (-8375 2600);
DISPLAY INVISIBLE (-8375 2600);
FORCEPROP 2 LAST CDS_LOCATION R608
J 0
(-8375 2650);
DISPLAY 1.021277 (-8375 2650);
DISPLAY INVISIBLE (-8375 2650);
FORCEPROP 2 LAST $SEC 1
J 0
(-8375 2650);
DISPLAY 0.680851 (-8375 2650);
PAINT MONO (-8375 2650);
DISPLAY INVISIBLE (-8375 2650);
FORCEPROP 2 LAST CDS_SEC 1
J 0
(-8375 2650);
DISPLAY 1.021277 (-8375 2650);
DISPLAY INVISIBLE (-8375 2650);
FORCEADD UNIVERSAL_GND..1
(-8425 2200);
FORCEPROP 3 LASTPIN (-8425 2250) SIG_NAME GND\g
J 0
(-8415 2260);
DISPLAY 0.659574 (-8415 2260);
PAINT MONO (-8415 2260);
DISPLAY INVISIBLE (-8415 2260);
FORCEPROP 2 LAST CDS_LIB logical_power
J 0
(-8425 2200);
PAINT MONO (-8425 2200);
DISPLAY INVISIBLE (-8425 2200);
FORCEPROP 1 LAST HDL_POWER GND
J 1
(-8400 2125);
DISPLAY 0.872340 (-8400 2125);
PAINT GREEN (-8400 2125);
DISPLAY INVISIBLE (-8400 2125);
FORCEPROP 1 LAST PATH I37
J 0
(-8350 2200);
DISPLAY 0.872340 (-8350 2200);
PAINT AQUA (-8350 2200);
DISPLAY INVISIBLE (-8350 2200);
FORCEPROP 2 LAST ROOM IO_SLOT
J 1
(-8650 2275);
DISPLAY 0.744681 (-8650 2275);
DISPLAY INVISIBLE (-8650 2275);
FORCEADD UNIVERSAL_POWER..1
(-8425 1200);
FORCEPROP 3 LASTPIN (-8425 1150) SIG_NAME P3V3_AUX\g
J 0
(-8415 1160);
DISPLAY 0.659574 (-8415 1160);
PAINT MONO (-8415 1160);
DISPLAY INVISIBLE (-8415 1160);
FORCEPROP 1 LAST HDL_POWER P3V3_AUX
J 1
(-8425 1250);
DISPLAY 0.872340 (-8425 1250);
PAINT GREEN (-8425 1250);
FORCEPROP 2 LAST CDS_LIB logical_power
J 0
(-8425 1200);
PAINT MONO (-8425 1200);
DISPLAY INVISIBLE (-8425 1200);
FORCEPROP 1 LAST PATH I38
J 0
(-8375 1225);
DISPLAY 0.872340 (-8375 1225);
PAINT AQUA (-8375 1225);
DISPLAY INVISIBLE (-8375 1225);
FORCEADD Q_RES..2
(-8425 950);
FORCEPROP 1 LAST PART_NUMBER CS21002FB06
J 0
(-8385 825);
DISPLAY 0.638298 (-8385 825);
DISPLAY INVISIBLE (-8385 825);
FORCEPROP 1 LAST WATTAGE 1/16W
J 0
(-8385 925);
DISPLAY 0.787234 (-8385 925);
FORCEPROP 1 LAST VALUE 1K
J 0
(-8380 1025);
DISPLAY 0.787234 (-8380 1025);
FORCEPROP 1 LAST MATERIAL EMPTY
J 0
(-8385 875);
DISPLAY 0.787234 (-8385 875);
FORCEPROP 1 LAST PACK_TYPE 0402LF
J 0
(-8385 775);
DISPLAY 0.787234 (-8385 775);
FORCEPROP 1 LAST TOLERANCE 1%
J 0
(-8380 975);
DISPLAY 0.787234 (-8380 975);
FORCEPROP 1 LAST $LOCATION R609
J 0
(-8380 1075);
DISPLAY 0.978723 (-8380 1075);
FORCEPROP 1 LASTPIN (-8425 1050) $PN 1
J 0
(-8420 1012);
DISPLAY 0.787234 (-8420 1012);
FORCEPROP 1 LASTPIN (-8425 850) $PN 2
J 0
(-8420 860);
DISPLAY 0.787234 (-8420 860);
FORCEPROP 2 LAST CDS_LIB pure_quanta
J 0
(-8425 950);
PAINT MONO (-8425 950);
DISPLAY INVISIBLE (-8425 950);
FORCEPROP 1 LAST PATH I39
J 0
(-8375 1125);
DISPLAY 0.978723 (-8375 1125);
PAINT WHITE (-8375 1125);
DISPLAY INVISIBLE (-8375 1125);
FORCEPROP 2 LAST CDS_LOCATION R609
J 0
(-8375 1175);
DISPLAY 1.021277 (-8375 1175);
DISPLAY INVISIBLE (-8375 1175);
FORCEPROP 2 LAST $SEC 1
J 0
(-8375 1175);
DISPLAY 0.680851 (-8375 1175);
PAINT MONO (-8375 1175);
DISPLAY INVISIBLE (-8375 1175);
FORCEPROP 2 LAST CDS_SEC 1
J 0
(-8375 1175);
DISPLAY 1.021277 (-8375 1175);
DISPLAY INVISIBLE (-8375 1175);
FORCEADD OFFPAGE..2
(-900 650);
FORCEPROP 2 LAST $XR0 182 
J 0
(-711 650);
DISPLAY 0.638298 (-711 650);
PAINT MONO (-711 650);
FORCEPROP 2 LAST CDS_LIB standard
J 0
(-900 650);
PAINT MONO (-900 650);
DISPLAY INVISIBLE (-900 650);
FORCEPROP 1 LAST OFFPAGE TRUE
J 0
(-575 525);
DISPLAY 0.872340 (-575 525);
DISPLAY INVISIBLE (-575 525);
FORCEPROP 1 LAST COMMENT_BODY TRUE
J 0
(-945 555);
DISPLAY 0.872340 (-945 555);
PAINT GREEN (-945 555);
DISPLAY INVISIBLE (-945 555);
FORCEPROP 2 LAST PATH I4
J 0
(-725 725);
DISPLAY 1.021277 (-725 725);
DISPLAY INVISIBLE (-725 725);
FORCEADD Q_RES..2
(-8425 425);
FORCEPROP 1 LAST PART_NUMBER CS31002FB08
J 0
(-8385 300);
DISPLAY 0.787234 (-8385 300);
DISPLAY INVISIBLE (-8385 300);
FORCEPROP 1 LAST MATERIAL CHIP
J 0
(-8385 350);
DISPLAY 0.787234 (-8385 350);
FORCEPROP 1 LAST TOLERANCE 1%
J 0
(-8380 450);
DISPLAY 0.787234 (-8380 450);
FORCEPROP 1 LAST VALUE 10K
J 0
(-8380 500);
DISPLAY 0.787234 (-8380 500);
FORCEPROP 1 LAST PACK_TYPE 0402LF
J 0
(-8385 250);
DISPLAY 0.787234 (-8385 250);
FORCEPROP 1 LAST WATTAGE 1/16W
J 0
(-8385 400);
DISPLAY 0.787234 (-8385 400);
FORCEPROP 1 LAST $LOCATION R610
J 0
(-8380 550);
DISPLAY 0.978723 (-8380 550);
FORCEPROP 1 LASTPIN (-8425 525) $PN 1
J 0
(-8420 487);
DISPLAY 0.787234 (-8420 487);
FORCEPROP 1 LASTPIN (-8425 325) $PN 2
J 0
(-8420 335);
DISPLAY 0.787234 (-8420 335);
FORCEPROP 2 LAST CDS_LIB pure_quanta
J 0
(-8425 425);
PAINT MONO (-8425 425);
DISPLAY INVISIBLE (-8425 425);
FORCEPROP 1 LAST PATH I40
J 0
(-8375 600);
DISPLAY 0.978723 (-8375 600);
PAINT WHITE (-8375 600);
DISPLAY INVISIBLE (-8375 600);
FORCEPROP 2 LAST CDS_LOCATION R610
J 0
(-8375 650);
DISPLAY 1.021277 (-8375 650);
DISPLAY INVISIBLE (-8375 650);
FORCEPROP 2 LAST $SEC 1
J 0
(-8375 650);
DISPLAY 0.680851 (-8375 650);
PAINT MONO (-8375 650);
DISPLAY INVISIBLE (-8375 650);
FORCEPROP 2 LAST CDS_SEC 1
J 0
(-8375 650);
DISPLAY 1.021277 (-8375 650);
DISPLAY INVISIBLE (-8375 650);
FORCEADD UNIVERSAL_GND..1
(-8425 200);
FORCEPROP 3 LASTPIN (-8425 250) SIG_NAME GND\g
J 0
(-8415 260);
DISPLAY 0.659574 (-8415 260);
PAINT MONO (-8415 260);
DISPLAY INVISIBLE (-8415 260);
FORCEPROP 2 LAST CDS_LIB logical_power
J 0
(-8425 200);
PAINT MONO (-8425 200);
DISPLAY INVISIBLE (-8425 200);
FORCEPROP 1 LAST HDL_POWER GND
J 1
(-8400 125);
DISPLAY 0.872340 (-8400 125);
PAINT GREEN (-8400 125);
DISPLAY INVISIBLE (-8400 125);
FORCEPROP 1 LAST PATH I41
J 0
(-8350 200);
DISPLAY 0.872340 (-8350 200);
PAINT AQUA (-8350 200);
DISPLAY INVISIBLE (-8350 200);
FORCEPROP 2 LAST ROOM IO_SLOT
J 1
(-8650 275);
DISPLAY 0.744681 (-8650 275);
DISPLAY INVISIBLE (-8650 275);
FORCEADD UNIVERSAL_POWER..1
(-8425 -850);
FORCEPROP 3 LASTPIN (-8425 -900) SIG_NAME P3V3_AUX\g
J 0
(-8415 -890);
DISPLAY 0.659574 (-8415 -890);
PAINT MONO (-8415 -890);
DISPLAY INVISIBLE (-8415 -890);
FORCEPROP 1 LAST HDL_POWER P3V3_AUX
J 1
(-8425 -800);
DISPLAY 0.872340 (-8425 -800);
PAINT GREEN (-8425 -800);
FORCEPROP 2 LAST CDS_LIB logical_power
J 0
(-8425 -850);
PAINT MONO (-8425 -850);
DISPLAY INVISIBLE (-8425 -850);
FORCEPROP 1 LAST PATH I42
J 0
(-8375 -825);
DISPLAY 0.872340 (-8375 -825);
PAINT AQUA (-8375 -825);
DISPLAY INVISIBLE (-8375 -825);
FORCEADD Q_RES..2
(-8425 -1100);
FORCEPROP 1 LAST PART_NUMBER CS21002FB06
J 0
(-8385 -1225);
DISPLAY 0.638298 (-8385 -1225);
DISPLAY INVISIBLE (-8385 -1225);
FORCEPROP 1 LAST VALUE 1K
J 0
(-8380 -1025);
DISPLAY 0.787234 (-8380 -1025);
FORCEPROP 1 LAST PACK_TYPE 0402LF
J 0
(-8385 -1275);
DISPLAY 0.787234 (-8385 -1275);
FORCEPROP 1 LAST WATTAGE 1/16W
J 0
(-8385 -1125);
DISPLAY 0.787234 (-8385 -1125);
FORCEPROP 1 LAST MATERIAL CHIP
J 0
(-8385 -1175);
DISPLAY 0.787234 (-8385 -1175);
FORCEPROP 1 LAST TOLERANCE 1%
J 0
(-8380 -1075);
DISPLAY 0.787234 (-8380 -1075);
FORCEPROP 1 LAST $LOCATION R611
J 0
(-8380 -975);
DISPLAY 0.978723 (-8380 -975);
FORCEPROP 1 LASTPIN (-8425 -1000) $PN 1
J 0
(-8420 -1038);
DISPLAY 0.787234 (-8420 -1038);
FORCEPROP 1 LASTPIN (-8425 -1200) $PN 2
J 0
(-8420 -1190);
DISPLAY 0.787234 (-8420 -1190);
FORCEPROP 2 LAST CDS_LIB pure_quanta
J 0
(-8425 -1100);
PAINT MONO (-8425 -1100);
DISPLAY INVISIBLE (-8425 -1100);
FORCEPROP 1 LAST PATH I43
J 0
(-8375 -925);
DISPLAY 0.978723 (-8375 -925);
PAINT WHITE (-8375 -925);
DISPLAY INVISIBLE (-8375 -925);
FORCEPROP 2 LAST CDS_LOCATION R611
J 0
(-8375 -875);
DISPLAY 1.021277 (-8375 -875);
DISPLAY INVISIBLE (-8375 -875);
FORCEPROP 2 LAST $SEC 1
J 0
(-8375 -875);
DISPLAY 0.680851 (-8375 -875);
PAINT MONO (-8375 -875);
DISPLAY INVISIBLE (-8375 -875);
FORCEPROP 2 LAST CDS_SEC 1
J 0
(-8375 -875);
DISPLAY 1.021277 (-8375 -875);
DISPLAY INVISIBLE (-8375 -875);
FORCEADD Q_RES..2
(-8425 -1625);
FORCEPROP 1 LAST PART_NUMBER CS31002FB08
J 0
(-8385 -1750);
DISPLAY 0.787234 (-8385 -1750);
DISPLAY INVISIBLE (-8385 -1750);
FORCEPROP 1 LAST TOLERANCE 1%
J 0
(-8380 -1600);
DISPLAY 0.787234 (-8380 -1600);
FORCEPROP 1 LAST VALUE 10K
J 0
(-8380 -1550);
DISPLAY 0.787234 (-8380 -1550);
FORCEPROP 1 LAST PACK_TYPE 0402LF
J 0
(-8385 -1800);
DISPLAY 0.787234 (-8385 -1800);
FORCEPROP 1 LAST MATERIAL EMPTY
J 0
(-8385 -1700);
DISPLAY 0.787234 (-8385 -1700);
PAINT RED (-8385 -1700);
FORCEPROP 1 LAST WATTAGE 1/16W
J 0
(-8385 -1650);
DISPLAY 0.787234 (-8385 -1650);
FORCEPROP 1 LAST $LOCATION R612
J 0
(-8380 -1500);
DISPLAY 0.978723 (-8380 -1500);
FORCEPROP 1 LASTPIN (-8425 -1525) $PN 1
J 0
(-8420 -1563);
DISPLAY 0.787234 (-8420 -1563);
FORCEPROP 1 LASTPIN (-8425 -1725) $PN 2
J 0
(-8420 -1715);
DISPLAY 0.787234 (-8420 -1715);
FORCEPROP 2 LAST CDS_LIB pure_quanta
J 0
(-8425 -1625);
PAINT MONO (-8425 -1625);
DISPLAY INVISIBLE (-8425 -1625);
FORCEPROP 1 LAST PATH I44
J 0
(-8375 -1450);
DISPLAY 0.978723 (-8375 -1450);
PAINT WHITE (-8375 -1450);
DISPLAY INVISIBLE (-8375 -1450);
FORCEPROP 2 LAST CDS_LOCATION R612
J 0
(-8375 -1400);
DISPLAY 1.021277 (-8375 -1400);
DISPLAY INVISIBLE (-8375 -1400);
FORCEPROP 2 LAST $SEC 1
J 0
(-8375 -1400);
DISPLAY 0.680851 (-8375 -1400);
PAINT MONO (-8375 -1400);
DISPLAY INVISIBLE (-8375 -1400);
FORCEPROP 2 LAST CDS_SEC 1
J 0
(-8375 -1400);
DISPLAY 1.021277 (-8375 -1400);
DISPLAY INVISIBLE (-8375 -1400);
FORCEADD UNIVERSAL_GND..1
(-8425 -1850);
FORCEPROP 3 LASTPIN (-8425 -1800) SIG_NAME GND\g
J 0
(-8415 -1790);
DISPLAY 0.659574 (-8415 -1790);
PAINT MONO (-8415 -1790);
DISPLAY INVISIBLE (-8415 -1790);
FORCEPROP 2 LAST CDS_LIB logical_power
J 0
(-8425 -1850);
PAINT MONO (-8425 -1850);
DISPLAY INVISIBLE (-8425 -1850);
FORCEPROP 1 LAST HDL_POWER GND
J 1
(-8400 -1925);
DISPLAY 0.872340 (-8400 -1925);
PAINT GREEN (-8400 -1925);
DISPLAY INVISIBLE (-8400 -1925);
FORCEPROP 1 LAST PATH I45
J 0
(-8350 -1850);
DISPLAY 0.872340 (-8350 -1850);
PAINT AQUA (-8350 -1850);
DISPLAY INVISIBLE (-8350 -1850);
FORCEPROP 2 LAST ROOM IO_SLOT
J 1
(-8650 -1775);
DISPLAY 0.744681 (-8650 -1775);
DISPLAY INVISIBLE (-8650 -1775);
FORCEADD OFFPAGE..2
(-900 2650);
FORCEPROP 2 LAST $XR0 184 
J 0
(-711 2650);
DISPLAY 0.638298 (-711 2650);
PAINT MONO (-711 2650);
FORCEPROP 2 LAST CDS_LIB standard
J 0
(-900 2650);
PAINT MONO (-900 2650);
DISPLAY INVISIBLE (-900 2650);
FORCEPROP 1 LAST OFFPAGE TRUE
J 0
(-575 2525);
DISPLAY 0.872340 (-575 2525);
DISPLAY INVISIBLE (-575 2525);
FORCEPROP 1 LAST COMMENT_BODY TRUE
J 0
(-945 2555);
DISPLAY 0.872340 (-945 2555);
PAINT GREEN (-945 2555);
DISPLAY INVISIBLE (-945 2555);
FORCEPROP 2 LAST PATH I46
J 0
(-725 2725);
DISPLAY 1.021277 (-725 2725);
DISPLAY INVISIBLE (-725 2725);
FORCEADD UNIVERSAL_POWER..1
(-2125 3200);
FORCEPROP 3 LASTPIN (-2125 3150) SIG_NAME P3V3_AUX\g
J 0
(-2115 3160);
DISPLAY 0.659574 (-2115 3160);
PAINT MONO (-2115 3160);
DISPLAY INVISIBLE (-2115 3160);
FORCEPROP 1 LAST HDL_POWER P3V3_AUX
J 1
(-2125 3250);
DISPLAY 0.872340 (-2125 3250);
PAINT GREEN (-2125 3250);
FORCEPROP 2 LAST CDS_LIB logical_power
J 0
(-2125 3200);
PAINT MONO (-2125 3200);
DISPLAY INVISIBLE (-2125 3200);
FORCEPROP 1 LAST PATH I47
J 0
(-2075 3225);
DISPLAY 0.872340 (-2075 3225);
PAINT AQUA (-2075 3225);
DISPLAY INVISIBLE (-2075 3225);
FORCEADD Q_RES..2
(-2125 2950);
FORCEPROP 1 LAST PART_NUMBER CS31002FB08
J 0
(-2085 2825);
DISPLAY 0.787234 (-2085 2825);
DISPLAY INVISIBLE (-2085 2825);
FORCEPROP 1 LAST PACK_TYPE 0402LF
J 0
(-2085 2775);
DISPLAY 0.787234 (-2085 2775);
FORCEPROP 1 LAST TOLERANCE 1%
J 0
(-2080 2975);
DISPLAY 0.787234 (-2080 2975);
FORCEPROP 1 LAST WATTAGE 1/16W
J 0
(-2085 2925);
DISPLAY 0.787234 (-2085 2925);
FORCEPROP 1 LAST MATERIAL CHIP
J 0
(-2085 2875);
DISPLAY 0.787234 (-2085 2875);
FORCEPROP 1 LAST VALUE 10K
J 0
(-2080 3025);
DISPLAY 0.787234 (-2080 3025);
FORCEPROP 1 LAST $LOCATION R619
J 0
(-2080 3075);
DISPLAY 0.978723 (-2080 3075);
FORCEPROP 1 LASTPIN (-2125 3050) $PN 1
J 0
(-2120 3012);
DISPLAY 0.787234 (-2120 3012);
FORCEPROP 1 LASTPIN (-2125 2850) $PN 2
J 0
(-2120 2860);
DISPLAY 0.787234 (-2120 2860);
FORCEPROP 2 LAST CDS_LIB pure_quanta
J 0
(-2125 2950);
PAINT MONO (-2125 2950);
DISPLAY INVISIBLE (-2125 2950);
FORCEPROP 1 LAST PATH I48
J 0
(-2075 3125);
DISPLAY 0.978723 (-2075 3125);
PAINT WHITE (-2075 3125);
DISPLAY INVISIBLE (-2075 3125);
FORCEPROP 2 LAST CDS_LOCATION R619
J 0
(-2075 3175);
DISPLAY 1.021277 (-2075 3175);
DISPLAY INVISIBLE (-2075 3175);
FORCEPROP 2 LAST $SEC 1
J 0
(-2075 3175);
DISPLAY 0.680851 (-2075 3175);
PAINT MONO (-2075 3175);
DISPLAY INVISIBLE (-2075 3175);
FORCEPROP 2 LAST CDS_SEC 1
J 0
(-2075 3175);
DISPLAY 1.021277 (-2075 3175);
DISPLAY INVISIBLE (-2075 3175);
FORCEADD OFFPAGE..2
(-900 -1400);
FORCEPROP 2 LAST $XR0 184 
J 0
(-711 -1400);
DISPLAY 0.638298 (-711 -1400);
PAINT MONO (-711 -1400);
FORCEPROP 2 LAST CDS_LIB standard
J 0
(-900 -1400);
PAINT MONO (-900 -1400);
DISPLAY INVISIBLE (-900 -1400);
FORCEPROP 1 LAST OFFPAGE TRUE
J 0
(-575 -1525);
DISPLAY 0.872340 (-575 -1525);
DISPLAY INVISIBLE (-575 -1525);
FORCEPROP 1 LAST COMMENT_BODY TRUE
J 0
(-945 -1495);
DISPLAY 0.872340 (-945 -1495);
PAINT GREEN (-945 -1495);
DISPLAY INVISIBLE (-945 -1495);
FORCEPROP 2 LAST PATH I5
J 0
(-725 -1325);
DISPLAY 1.021277 (-725 -1325);
DISPLAY INVISIBLE (-725 -1325);
FORCEADD Q_RES..2
(-5300 950);
FORCEPROP 1 LAST PART_NUMBER CS21002FB06
J 0
(-5260 825);
DISPLAY 0.787234 (-5260 825);
DISPLAY INVISIBLE (-5260 825);
FORCEPROP 1 LAST PACK_TYPE 0402LF
J 0
(-5260 775);
DISPLAY 0.787234 (-5260 775);
FORCEPROP 1 LAST VALUE 1K
J 0
(-5255 1025);
DISPLAY 0.787234 (-5255 1025);
FORCEPROP 1 LAST MATERIAL CHIP
J 0
(-5260 875);
DISPLAY 0.787234 (-5260 875);
FORCEPROP 1 LAST WATTAGE 1/16W
J 0
(-5260 925);
DISPLAY 0.787234 (-5260 925);
FORCEPROP 1 LAST TOLERANCE 1%
J 0
(-5255 975);
DISPLAY 0.787234 (-5255 975);
FORCEPROP 1 LAST $LOCATION R615
J 0
(-5255 1075);
DISPLAY 0.978723 (-5255 1075);
FORCEPROP 1 LASTPIN (-5300 1050) $PN 1
J 0
(-5295 1012);
DISPLAY 0.787234 (-5295 1012);
FORCEPROP 1 LASTPIN (-5300 850) $PN 2
J 0
(-5295 860);
DISPLAY 0.787234 (-5295 860);
FORCEPROP 2 LAST CDS_LIB pure_quanta
J 0
(-5300 950);
PAINT MONO (-5300 950);
DISPLAY INVISIBLE (-5300 950);
FORCEPROP 1 LAST PATH I51
J 0
(-5250 1125);
DISPLAY 0.978723 (-5250 1125);
PAINT WHITE (-5250 1125);
DISPLAY INVISIBLE (-5250 1125);
FORCEPROP 2 LAST CDS_LOCATION R615
J 0
(-5250 1175);
DISPLAY 1.021277 (-5250 1175);
DISPLAY INVISIBLE (-5250 1175);
FORCEPROP 2 LAST $SEC 1
J 0
(-5250 1175);
DISPLAY 0.680851 (-5250 1175);
PAINT MONO (-5250 1175);
DISPLAY INVISIBLE (-5250 1175);
FORCEPROP 2 LAST CDS_SEC 1
J 0
(-5250 1175);
DISPLAY 1.021277 (-5250 1175);
DISPLAY INVISIBLE (-5250 1175);
FORCEADD Q_RES..2
(-5300 -1625);
FORCEPROP 1 LAST PART_NUMBER CS31002FB08
J 0
(-5260 -1750);
DISPLAY 0.787234 (-5260 -1750);
DISPLAY INVISIBLE (-5260 -1750);
FORCEPROP 1 LAST VALUE 10K
J 0
(-5255 -1550);
DISPLAY 0.787234 (-5255 -1550);
FORCEPROP 1 LAST TOLERANCE 1%
J 0
(-5255 -1600);
DISPLAY 0.787234 (-5255 -1600);
FORCEPROP 1 LAST MATERIAL CHIP
J 0
(-5260 -1700);
DISPLAY 0.787234 (-5260 -1700);
FORCEPROP 1 LAST PACK_TYPE 0402LF
J 0
(-5260 -1800);
DISPLAY 0.787234 (-5260 -1800);
FORCEPROP 1 LAST WATTAGE 1/16W
J 0
(-5260 -1650);
DISPLAY 0.787234 (-5260 -1650);
FORCEPROP 1 LAST $LOCATION R618
J 0
(-5255 -1500);
DISPLAY 0.978723 (-5255 -1500);
FORCEPROP 1 LASTPIN (-5300 -1525) $PN 1
J 0
(-5295 -1563);
DISPLAY 0.787234 (-5295 -1563);
FORCEPROP 1 LASTPIN (-5300 -1725) $PN 2
J 0
(-5295 -1715);
DISPLAY 0.787234 (-5295 -1715);
FORCEPROP 2 LAST CDS_LIB pure_quanta
J 0
(-5300 -1625);
PAINT MONO (-5300 -1625);
DISPLAY INVISIBLE (-5300 -1625);
FORCEPROP 1 LAST PATH I53
J 0
(-5250 -1450);
DISPLAY 0.978723 (-5250 -1450);
PAINT WHITE (-5250 -1450);
DISPLAY INVISIBLE (-5250 -1450);
FORCEPROP 2 LAST CDS_LOCATION R618
J 0
(-5250 -1400);
DISPLAY 1.021277 (-5250 -1400);
DISPLAY INVISIBLE (-5250 -1400);
FORCEPROP 2 LAST $SEC 1
J 0
(-5250 -1400);
DISPLAY 0.680851 (-5250 -1400);
PAINT MONO (-5250 -1400);
DISPLAY INVISIBLE (-5250 -1400);
FORCEPROP 2 LAST CDS_SEC 1
J 0
(-5250 -1400);
DISPLAY 1.021277 (-5250 -1400);
DISPLAY INVISIBLE (-5250 -1400);
FORCEADD Q_RES..2
(-5300 -1150);
FORCEPROP 1 LAST PART_NUMBER CS21002FB06
J 0
(-5260 -1275);
DISPLAY 0.638298 (-5260 -1275);
DISPLAY INVISIBLE (-5260 -1275);
FORCEPROP 1 LAST WATTAGE 1/16W
J 0
(-5260 -1175);
DISPLAY 0.787234 (-5260 -1175);
FORCEPROP 1 LAST VALUE 1K
J 0
(-5255 -1075);
DISPLAY 0.787234 (-5255 -1075);
FORCEPROP 1 LAST MATERIAL EMPTY
J 0
(-5260 -1225);
DISPLAY 0.787234 (-5260 -1225);
FORCEPROP 1 LAST PACK_TYPE 0402LF
J 0
(-5260 -1325);
DISPLAY 0.787234 (-5260 -1325);
FORCEPROP 1 LAST TOLERANCE 1%
J 0
(-5255 -1125);
DISPLAY 0.787234 (-5255 -1125);
FORCEPROP 1 LAST $LOCATION R617
J 0
(-5255 -1025);
DISPLAY 0.978723 (-5255 -1025);
FORCEPROP 1 LASTPIN (-5300 -1050) $PN 1
J 0
(-5295 -1088);
DISPLAY 0.787234 (-5295 -1088);
FORCEPROP 1 LASTPIN (-5300 -1250) $PN 2
J 0
(-5295 -1240);
DISPLAY 0.787234 (-5295 -1240);
FORCEPROP 2 LAST CDS_LIB pure_quanta
J 0
(-5300 -1150);
PAINT MONO (-5300 -1150);
DISPLAY INVISIBLE (-5300 -1150);
FORCEPROP 1 LAST PATH I54
J 0
(-5250 -975);
DISPLAY 0.978723 (-5250 -975);
PAINT WHITE (-5250 -975);
DISPLAY INVISIBLE (-5250 -975);
FORCEPROP 2 LAST CDS_LOCATION R617
J 0
(-5250 -925);
DISPLAY 1.021277 (-5250 -925);
DISPLAY INVISIBLE (-5250 -925);
FORCEPROP 2 LAST $SEC 1
J 0
(-5250 -925);
DISPLAY 0.680851 (-5250 -925);
PAINT MONO (-5250 -925);
DISPLAY INVISIBLE (-5250 -925);
FORCEPROP 2 LAST CDS_SEC 1
J 0
(-5250 -925);
DISPLAY 1.021277 (-5250 -925);
DISPLAY INVISIBLE (-5250 -925);
FORCEADD Q_RES..2
(-2125 900);
FORCEPROP 1 LAST PART_NUMBER CS21002FB06
J 0
(-2085 775);
DISPLAY 0.638298 (-2085 775);
DISPLAY INVISIBLE (-2085 775);
FORCEPROP 1 LAST PACK_TYPE 0402LF
J 0
(-2085 725);
DISPLAY 0.787234 (-2085 725);
FORCEPROP 1 LAST MATERIAL EMPTY
J 0
(-2085 825);
DISPLAY 0.787234 (-2085 825);
FORCEPROP 1 LAST WATTAGE 1/16W
J 0
(-2085 875);
DISPLAY 0.787234 (-2085 875);
FORCEPROP 1 LAST VALUE 1K
J 0
(-2080 975);
DISPLAY 0.787234 (-2080 975);
FORCEPROP 1 LAST TOLERANCE 1%
J 0
(-2080 925);
DISPLAY 0.787234 (-2080 925);
FORCEPROP 1 LAST $LOCATION R621
J 0
(-2080 1025);
DISPLAY 0.978723 (-2080 1025);
FORCEPROP 1 LASTPIN (-2125 1000) $PN 1
J 0
(-2120 962);
DISPLAY 0.787234 (-2120 962);
FORCEPROP 1 LASTPIN (-2125 800) $PN 2
J 0
(-2120 810);
DISPLAY 0.787234 (-2120 810);
FORCEPROP 2 LAST CDS_LIB pure_quanta
J 0
(-2125 900);
PAINT MONO (-2125 900);
DISPLAY INVISIBLE (-2125 900);
FORCEPROP 1 LAST PATH I55
J 0
(-2075 1075);
DISPLAY 0.978723 (-2075 1075);
PAINT WHITE (-2075 1075);
DISPLAY INVISIBLE (-2075 1075);
FORCEPROP 2 LAST CDS_LOCATION R621
J 0
(-2075 1125);
DISPLAY 1.021277 (-2075 1125);
DISPLAY INVISIBLE (-2075 1125);
FORCEPROP 2 LAST $SEC 1
J 0
(-2075 1125);
DISPLAY 0.680851 (-2075 1125);
PAINT MONO (-2075 1125);
DISPLAY INVISIBLE (-2075 1125);
FORCEPROP 2 LAST CDS_SEC 1
J 0
(-2075 1125);
DISPLAY 1.021277 (-2075 1125);
DISPLAY INVISIBLE (-2075 1125);
FORCEADD Q_RES..2
(-2125 425);
FORCEPROP 1 LAST PART_NUMBER CS21002FB06
J 0
(-2085 300);
DISPLAY 0.787234 (-2085 300);
DISPLAY INVISIBLE (-2085 300);
FORCEPROP 1 LAST WATTAGE 1/16W
J 0
(-2085 400);
DISPLAY 0.787234 (-2085 400);
FORCEPROP 1 LAST MATERIAL CHIP
J 0
(-2085 350);
DISPLAY 0.787234 (-2085 350);
FORCEPROP 1 LAST PACK_TYPE 0402LF
J 0
(-2085 250);
DISPLAY 0.787234 (-2085 250);
FORCEPROP 1 LAST VALUE 1K
J 0
(-2080 500);
DISPLAY 0.787234 (-2080 500);
FORCEPROP 1 LAST TOLERANCE 1%
J 0
(-2080 450);
DISPLAY 0.787234 (-2080 450);
FORCEPROP 1 LAST $LOCATION R622
J 0
(-2080 550);
DISPLAY 0.978723 (-2080 550);
FORCEPROP 1 LASTPIN (-2125 525) $PN 1
J 0
(-2120 487);
DISPLAY 0.787234 (-2120 487);
FORCEPROP 1 LASTPIN (-2125 325) $PN 2
J 0
(-2120 335);
DISPLAY 0.787234 (-2120 335);
FORCEPROP 2 LAST CDS_LIB pure_quanta
J 0
(-2125 425);
PAINT MONO (-2125 425);
DISPLAY INVISIBLE (-2125 425);
FORCEPROP 1 LAST PATH I56
J 0
(-2075 600);
DISPLAY 0.978723 (-2075 600);
PAINT WHITE (-2075 600);
DISPLAY INVISIBLE (-2075 600);
FORCEPROP 2 LAST CDS_LOCATION R622
J 0
(-2075 650);
DISPLAY 1.021277 (-2075 650);
DISPLAY INVISIBLE (-2075 650);
FORCEPROP 2 LAST $SEC 1
J 0
(-2075 650);
DISPLAY 0.680851 (-2075 650);
PAINT MONO (-2075 650);
DISPLAY INVISIBLE (-2075 650);
FORCEPROP 2 LAST CDS_SEC 1
J 0
(-2075 650);
DISPLAY 1.021277 (-2075 650);
DISPLAY INVISIBLE (-2075 650);
FORCEADD UNIVERSAL_POWER..1
(-2125 1150);
FORCEPROP 3 LASTPIN (-2125 1100) SIG_NAME P3V3_AUX\g
J 0
(-2115 1110);
DISPLAY 0.659574 (-2115 1110);
PAINT MONO (-2115 1110);
DISPLAY INVISIBLE (-2115 1110);
FORCEPROP 1 LAST HDL_POWER P3V3_AUX
J 1
(-2125 1200);
DISPLAY 0.872340 (-2125 1200);
PAINT GREEN (-2125 1200);
FORCEPROP 2 LAST CDS_LIB logical_power
J 0
(-2125 1150);
PAINT MONO (-2125 1150);
DISPLAY INVISIBLE (-2125 1150);
FORCEPROP 1 LAST PATH I8
J 0
(-2075 1175);
DISPLAY 0.872340 (-2075 1175);
PAINT AQUA (-2075 1175);
DISPLAY INVISIBLE (-2075 1175);
FORCEADD DNS..2
(-2120 -1155);
PAINT RED (-2120 -1155);
FORCEPROP 2 LAST CDS_LIB mstr_misc
J 0
(-2120 -1155);
PAINT MONO (-2120 -1155);
DISPLAY INVISIBLE (-2120 -1155);
FORCEPROP 1 LAST COMMENT_BODY TRUE
J 0
(-2120 -1155);
DISPLAY INVISIBLE (-2120 -1155);
FORCEADD DNS..2
(-5295 2395);
PAINT RED (-5295 2395);
FORCEPROP 2 LAST CDS_LIB mstr_misc
J 0
(-5295 2395);
PAINT MONO (-5295 2395);
DISPLAY INVISIBLE (-5295 2395);
FORCEPROP 1 LAST COMMENT_BODY TRUE
J 0
(-5295 2395);
DISPLAY INVISIBLE (-5295 2395);
FORCEADD DNS..2
(-8420 -1630);
PAINT RED (-8420 -1630);
FORCEPROP 2 LAST CDS_LIB mstr_misc
J 0
(-8420 -1630);
PAINT MONO (-8420 -1630);
DISPLAY INVISIBLE (-8420 -1630);
FORCEPROP 1 LAST COMMENT_BODY TRUE
J 0
(-8420 -1630);
DISPLAY INVISIBLE (-8420 -1630);
FORCEADD DNS..2
(-8420 920);
PAINT RED (-8420 920);
FORCEPROP 2 LAST CDS_LIB mstr_misc
J 0
(-8420 920);
PAINT MONO (-8420 920);
DISPLAY INVISIBLE (-8420 920);
FORCEPROP 1 LAST COMMENT_BODY TRUE
J 0
(-8420 920);
DISPLAY INVISIBLE (-8420 920);
FORCEADD DNS..2
(-5295 -1180);
PAINT RED (-5295 -1180);
FORCEPROP 2 LAST CDS_LIB mstr_misc
J 0
(-5295 -1180);
PAINT MONO (-5295 -1180);
DISPLAY INVISIBLE (-5295 -1180);
FORCEPROP 1 LAST COMMENT_BODY TRUE
J 0
(-5295 -1180);
DISPLAY INVISIBLE (-5295 -1180);
FORCEADD DNS..2
(-8420 2920);
PAINT RED (-8420 2920);
FORCEPROP 2 LAST CDS_LIB mstr_misc
J 0
(-8420 2920);
PAINT MONO (-8420 2920);
DISPLAY INVISIBLE (-8420 2920);
FORCEPROP 1 LAST COMMENT_BODY TRUE
J 0
(-8420 2920);
DISPLAY INVISIBLE (-8420 2920);
FORCEADD DNS..2
(-2120 870);
PAINT RED (-2120 870);
FORCEPROP 2 LAST CDS_LIB mstr_misc
J 0
(-2120 870);
PAINT MONO (-2120 870);
DISPLAY INVISIBLE (-2120 870);
FORCEPROP 1 LAST COMMENT_BODY TRUE
J 0
(-2120 870);
DISPLAY INVISIBLE (-2120 870);
FORCEADD QUANTA_TITLE_BLOCK_C..1
(125 -2425);
FORCEPROP 0 LAST CDS_CON_LAST_MODIFIED Fri Aug 25 14:03:14 2023
J 0
(-1760 -2410);
PAINT MONO (-1760 -2410);
DISPLAY INVISIBLE (-1760 -2410);
FORCEPROP 2 LAST CUSTOM_TXT_CDS <XR_PAGE_TITLE>
J 0
(-7765 2825);
DISPLAY 0.638298 (-7765 2825);
PAINT PINK (-7765 2825);
DISPLAY INVISIBLE (-7765 2825);
FORCEPROP 2 LAST CUSTOM_TXT_CDS CR-166 : @ES_MB_LIB.ES_MB(SCH_1):PAGE166
J 0
(-7765 2825);
DISPLAY 0.638298 (-7765 2825);
PAINT PINK (-7765 2825);
DISPLAY INVISIBLE (-7765 2825);
FORCEPROP 2 LAST CUSTOM_TXT_CDS <Q_NUMBER>
J 0
(-1278 -2322);
DISPLAY 1.212766 (-1278 -2322);
FORCEPROP 2 LAST CUSTOM_TXT_CDS <CON_LAST_MODIFIED>
J 0
(-1760 -2410);
DISPLAY 0.978723 (-1760 -2410);
FORCEPROP 1 LAST CUSTOM_TXT_CDS <NAME_2>
J 0
(-3050 -2375);
FORCEPROP 1 LAST CUSTOM_TXT_CDS <NAME_1>
J 0
(-3050 -2250);
FORCEPROP 1 LAST CUSTOM_TXT_CDS <Q_PROJ>
J 0
(-2257 -2323);
DISPLAY 1.212766 (-2257 -2323);
FORCEPROP 1 LAST CUSTOM_TXT_CDS <Q_REV>
J 0
(-59 -2322);
DISPLAY 1.212766 (-59 -2322);
FORCEPROP 1 LAST CUSTOM_TXT_CDS <CON_PAGE_NUM> OF <CON_TOTAL_PAGES>
J 0
(-321 -2407);
DISPLAY 0.978723 (-321 -2407);
FORCEPROP 1 LAST Q_TITLE PCH SIDEBAND: HW STRAPS (2/4)
J 0
(-9216 -2399);
DISPLAY 1.957447 (-9216 -2399);
PAINT GREEN (-9216 -2399);
FORCEPROP 1 LAST Q_DEPT 
J 1
(-3638 -2376);
DISPLAY 1.957447 (-3638 -2376);
PAINT GREEN (-3638 -2376);
FORCEPROP 2 LAST CDS_XR_PAGE_TITLE CR-199 : @S9S_MB_2U_LIB.S9S_MB_2U(SCH_1):PAGE199
J 0
(-7765 2825);
DISPLAY 0.638298 (-7765 2825);
PAINT PINK (-7765 2825);
DISPLAY INVISIBLE (-7765 2825);
FORCEPROP 1 LAST COMMENT_BODY TRUE
J 0
(137 -2438);
DISPLAY 0.978723 (137 -2438);
PAINT GREEN (137 -2438);
DISPLAY INVISIBLE (137 -2438);
FORCEPROP 2 LAST CDS_LIB pure_quanta
J 0
(125 -2425);
PAINT MONO (125 -2425);
DISPLAY INVISIBLE (125 -2425);
FORCEPROP 1 LAST CDS_LMAN_SYM_OUTLINE -9475,6775,100,-125
J 0
(125 -2425);
DISPLAY 0.468085 (125 -2425);
PAINT GREEN (125 -2425);
DISPLAY INVISIBLE (125 -2425);
FORCEPROP 2 LAST PAGE_BORDER TRUE
J 0
(-7765 2825);
DISPLAY 0.638298 (-7765 2825);
PAINT PINK (-7765 2825);
DISPLAY INVISIBLE (-7765 2825);
WIRE 16 -1 (-2125 1000)(-2125 1100);
WIRE 16 -1 (-2125 3050)(-2125 3150);
WIRE 16 -1 (-8425 -1000)(-8425 -900);
WIRE 16 -1 (-8425 1050)(-8425 1150);
WIRE 16 -1 (-5300 -1050)(-5300 -950);
WIRE 16 -1 (-5300 1050)(-5300 1150);
WIRE 16 -1 (-8425 3050)(-8425 3150);
WIRE 16 -1 (-5300 3050)(-5300 3150);
WIRE 16 -1 (-2125 -1025)(-2125 -925);
WIRE 16 -1 (-8425 -1800)(-8425 -1725);
WIRE 16 -1 (-8425 250)(-8425 325);
WIRE 16 -1 (-8425 2250)(-8425 2325);
WIRE 16 -1 (-5300 -1800)(-5300 -1725);
WIRE 16 -1 (-5300 2250)(-5300 2325);
WIRE 16 -1 (-2125 -1825)(-2125 -1750);
WIRE 16 -1 (-2125 250)(-2125 325);
WIRE 16 273 (-6200 3875)(-6200 -1975);
WIRE 16 3135 (-1325 -1750)(-1325 -1875);
WIRE 16 3135 (-1325 -1625)(-1325 -1750);
WIRE 16 3135 (-1325 -1875)(-1175 -1875);
WIRE 16 3135 (-1175 -1875)(-500 -1875);
WIRE 16 3135 (-1175 -1750)(-1325 -1750);
WIRE 16 3135 (-1175 -1750)(-1175 -1875);
WIRE 16 3135 (-1175 -1625)(-1325 -1625);
WIRE 16 3135 (-1175 -1625)(-1175 -1750);
WIRE 16 3135 (-500 -1625)(-1175 -1625);
WIRE 16 3135 (-500 -1750)(-1175 -1750);
WIRE 16 3135 (-500 -1875)(-500 -1750);
WIRE 16 3135 (-500 -1750)(-500 -1625);
WIRE 16 -1 (-2125 -1550)(-2125 -1400);
WIRE 16 -1 (-2125 -1400)(-2125 -1225);
WIRE 16 -1 (-2125 -1400)(-950 -1400);
FORCEPROP 2 LAST SIG_NAME FM_PCH_XTALSEL
J 0
(-1935 -1390);
DISPLAY 0.808511 (-1935 -1390);
PAINT WHITE (-1935 -1390);
WIRE 16 273 (-2850 -1975)(-2850 3925);
WIRE 16 -1 (-5300 650)(-5300 850);
WIRE 16 -1 (-4100 650)(-5300 650);
FORCEPROP 2 LAST SIG_NAME FM_PCH_VISA_DEFAULT
J 0
(-5110 660);
DISPLAY 0.808511 (-5110 660);
PAINT WHITE (-5110 660);
WIRE 16 -1 (-8425 2650)(-8425 2525);
WIRE 16 -1 (-8425 2850)(-8425 2650);
WIRE 16 -1 (-8425 2650)(-7225 2650);
FORCEPROP 2 LAST SIG_NAME FM_ESPI_FLASH_MODE
J 0
(-8285 2660);
DISPLAY 0.808511 (-8285 2660);
PAINT WHITE (-8285 2660);
WIRE 16 -1 (-2125 525)(-2125 650);
WIRE 16 -1 (-2125 650)(-2125 800);
WIRE 16 -1 (-2125 650)(-950 650);
FORCEPROP 2 LAST SIG_NAME FM_PCH_SKIP_RTC_CLOCK
J 0
(-1935 660);
DISPLAY 0.808511 (-1935 660);
PAINT WHITE (-1935 660);
WIRE 16 -1 (-8425 -1400)(-8425 -1525);
WIRE 16 -1 (-8425 -1200)(-8425 -1400);
WIRE 16 -1 (-7225 -1400)(-8425 -1400);
FORCEPROP 2 LAST SIG_NAME FM_PCH_EXTERNALCLKMODE
J 0
(-8135 -1390);
DISPLAY 0.808511 (-8135 -1390);
PAINT WHITE (-8135 -1390);
WIRE 16 -1 (-8425 650)(-8425 525);
WIRE 16 -1 (-8425 850)(-8425 650);
WIRE 16 -1 (-7225 650)(-8425 650);
FORCEPROP 2 LAST SIG_NAME FM_ESPI_CS_SWIZZLE
J 0
(-8285 660);
DISPLAY 0.808511 (-8285 660);
PAINT WHITE (-8285 660);
WIRE 16 -1 (-5300 2525)(-5300 2650);
WIRE 16 -1 (-5300 2650)(-5300 2850);
WIRE 16 -1 (-4100 2650)(-5300 2650);
FORCEPROP 0 LAST CDS_PHYS_NET_NAME FM_JTAG_ODT_DISABLE
J 0
(-5085 2698);
PAINT MONO (-5085 2698);
DISPLAY INVISIBLE (-5085 2698);
FORCEPROP 2 LAST SIG_NAME FM_JTAG_ODT_DISABLE
J 0
(-5110 2660);
DISPLAY 0.808511 (-5110 2660);
PAINT WHITE (-5110 2660);
WIRE 16 -1 (-5300 -1400)(-5300 -1525);
WIRE 16 -1 (-5300 -1250)(-5300 -1400);
WIRE 16 -1 (-4100 -1400)(-5300 -1400);
FORCEPROP 2 LAST SIG_NAME FM_PCH_IO_EXPANDER
J 0
(-5110 -1390);
DISPLAY 0.808511 (-5110 -1390);
PAINT WHITE (-5110 -1390);
WIRE 16 -1 (-2125 2650)(-2125 2850);
WIRE 16 -1 (-2125 2650)(-950 2650);
FORCEPROP 2 LAST SIG_NAME FM_LT_KEY_DOWNGRADE_N
J 0
(-1935 2660);
DISPLAY 0.808511 (-1935 2660);
PAINT WHITE (-1935 2660);
WIRE 16 3135 (-1325 300)(-1325 100);
WIRE 16 3135 (-1325 425)(-1325 300);
WIRE 16 3135 (-1325 100)(-1175 100);
WIRE 16 3135 (-1175 100)(-25 100);
WIRE 16 3135 (-1175 300)(-1325 300);
WIRE 16 3135 (-1175 300)(-1175 100);
WIRE 16 3135 (-1175 425)(-1325 425);
WIRE 16 3135 (-1175 425)(-1175 300);
WIRE 16 3135 (-25 425)(-1175 425);
WIRE 16 3135 (-25 300)(-1175 300);
WIRE 16 3135 (-25 100)(-25 300);
WIRE 16 3135 (-25 300)(-25 425);
WIRE 16 273 (-200 -25)(-9000 -25);
WIRE 16 273 (-9000 2050)(-200 2050);
DOT 1 (-1175 300);
DOT 1 (-1175 -1625);
DOT 1 (-1175 -1875);
DOT 1 (-1325 -1750);
DOT 1 (-1175 -1750);
DOT 1 (-500 -1750);
DOT 1 (-1175 425);
DOT 1 (-25 300);
DOT 1 (-2125 -1400);
DOT 1 (-8425 2650);
DOT 1 (-5300 2650);
DOT 1 (-5300 -1400);
DOT 1 (-2125 650);
DOT 1 (-8425 650);
DOT 1 (-1175 100);
DOT 1 (-1325 300);
DOT 1 (-8425 -1400);
FORCENOTE
BYPASS/SKIP 95MS RTC CLOCK
(-1125 225) 0;
DISPLAY LEFT (-1125 225);
DISPLAY 0.808511 (-1125 225);
PAINT YELLOW (-1125 225);
FORCENOTE
STABILIZATION DELAY
(-1125 150) 0;
DISPLAY LEFT (-1125 150);
DISPLAY 0.808511 (-1125 150);
PAINT YELLOW (-1125 150);
FORCENOTE
DEFAULT: 0 (CS0/CS1 PINS NO SWIZZLE)
(-8835 1569) 0;
DISPLAY LEFT (-8835 1569);
DISPLAY 1.276596 (-8835 1569);
PAINT YELLOW (-8835 1569);
FORCENOTE
FUNCTION:ESPI CS SWIZZLE
(-8835 1669) 0;
DISPLAY LEFT (-8835 1669);
DISPLAY 1.276596 (-8835 1669);
PAINT YELLOW (-8835 1669);
FORCENOTE
PCH INTERNAL: PULL DOWN
(-5710 -606) 0;
DISPLAY LEFT (-5710 -606);
DISPLAY 1.276596 (-5710 -606);
PAINT YELLOW (-5710 -606);
FORCENOTE
FUNCTION:I/O EXPANDER
(-5710 -406) 0;
DISPLAY LEFT (-5710 -406);
DISPLAY 1.276596 (-5710 -406);
PAINT YELLOW (-5710 -406);
FORCENOTE
GROUP: GPP_O_7
(-2560 1769) 0;
DISPLAY LEFT (-2560 1769);
DISPLAY 1.276596 (-2560 1769);
PAINT YELLOW (-2560 1769);
FORCENOTE
GROUP: GPPC_H_1
(-5710 -306) 0;
DISPLAY LEFT (-5710 -306);
DISPLAY 1.276596 (-5710 -306);
PAINT YELLOW (-5710 -306);
FORCENOTE
DEFAULT: 0 (PCH MODE)
(-5710 -506) 0;
DISPLAY LEFT (-5710 -506);
DISPLAY 1.276596 (-5710 -506);
PAINT YELLOW (-5710 -506);
FORCENOTE
GROUP: GPPC_H_6
(-8835 -306) 0;
DISPLAY LEFT (-8835 -306);
DISPLAY 1.276596 (-8835 -306);
PAINT YELLOW (-8835 -306);
FORCENOTE
FUNCTION:EXTERNAL CLK MODE
(-8835 -406) 0;
DISPLAY LEFT (-8835 -406);
DISPLAY 1.276596 (-8835 -406);
PAINT YELLOW (-8835 -406);
FORCENOTE
PD  25MHZ (DEFAULT)
(-1275 -1700) 0;
DISPLAY LEFT (-1275 -1700);
DISPLAY 0.808511 (-1275 -1700);
PAINT YELLOW (-1275 -1700);
FORCENOTE
PU  100MHZ
(-1275 -1825) 0;
DISPLAY LEFT (-1275 -1825);
DISPLAY 0.808511 (-1275 -1825);
PAINT YELLOW (-1275 -1825);
FORCENOTE
DEFAULT: 0 
(-2560 1569) 0;
DISPLAY LEFT (-2560 1569);
DISPLAY 1.276596 (-2560 1569);
PAINT YELLOW (-2560 1569);
FORCENOTE
PCH INTERNAL: PULL DOWN
(-5710 1469) 0;
DISPLAY LEFT (-5710 1469);
DISPLAY 1.276596 (-5710 1469);
PAINT YELLOW (-5710 1469);
FORCENOTE
PCH INTERNAL: PULL DOWN
(-8835 3469) 0;
DISPLAY LEFT (-8835 3469);
DISPLAY 1.276596 (-8835 3469);
PAINT YELLOW (-8835 3469);
FORCENOTE
FUNCTION:ESPI FLASH MODE
(-8835 3669) 0;
DISPLAY LEFT (-8835 3669);
DISPLAY 1.276596 (-8835 3669);
PAINT YELLOW (-8835 3669);
FORCENOTE
GROUP: GPP_D_7
(-8835 3769) 0;
DISPLAY LEFT (-8835 3769);
DISPLAY 1.276596 (-8835 3769);
PAINT YELLOW (-8835 3769);
FORCENOTE
FOLLOW ARCHER CITY DESIGN TO RESERVE
(-2535 3469) 0;
DISPLAY LEFT (-2535 3469);
DISPLAY 1.276596 (-2535 3469);
PAINT YELLOW (-2535 3469);
FORCENOTE
DEFAULT: 1 
(-2535 3569) 0;
DISPLAY LEFT (-2535 3569);
DISPLAY 1.276596 (-2535 3569);
PAINT YELLOW (-2535 3569);
FORCENOTE
FUNCTION:RSVD (PCH TEST MODE)
(-2535 3669) 0;
DISPLAY LEFT (-2535 3669);
DISPLAY 1.276596 (-2535 3669);
PAINT YELLOW (-2535 3669);
FORCENOTE
GROUP: GPPC_H_19
(-2535 3769) 0;
DISPLAY LEFT (-2535 3769);
DISPLAY 1.276596 (-2535 3769);
PAINT YELLOW (-2535 3769);
FORCENOTE
DEFAULT: 0 (ISCLK USES 25MHZ XTAL)
(-8835 -506) 0;
DISPLAY LEFT (-8835 -506);
DISPLAY 1.276596 (-8835 -506);
PAINT YELLOW (-8835 -506);
FORCENOTE
GROUP: GPPC_S_11
(-8835 1769) 0;
DISPLAY LEFT (-8835 1769);
DISPLAY 1.276596 (-8835 1769);
PAINT YELLOW (-8835 1769);
FORCENOTE
PCH INTERNAL: PULL DOWN
(-8835 -606) 0;
DISPLAY LEFT (-8835 -606);
DISPLAY 1.276596 (-8835 -606);
PAINT YELLOW (-8835 -606);
FORCENOTE
GROUP: GPPC_S_10
(-5710 3769) 0;
DISPLAY LEFT (-5710 3769);
DISPLAY 1.276596 (-5710 3769);
PAINT YELLOW (-5710 3769);
FORCENOTE
DEFAULT: 1 (ODT IS ENABLED)
(-5710 3569) 0;
DISPLAY LEFT (-5710 3569);
DISPLAY 1.276596 (-5710 3569);
PAINT YELLOW (-5710 3569);
FORCENOTE
FUNCTION:JTAG ODT DISABLE
(-5710 3669) 0;
DISPLAY LEFT (-5710 3669);
DISPLAY 1.276596 (-5710 3669);
PAINT YELLOW (-5710 3669);
FORCENOTE
FOLLOW ARCHER CITY DESIGN TO RESERVE
(-5710 3469) 0;
DISPLAY LEFT (-5710 3469);
DISPLAY 1.276596 (-5710 3469);
PAINT YELLOW (-5710 3469);
FORCENOTE
PD  NO BYPASS (DEFAULT)
(-1275 350) 0;
DISPLAY LEFT (-1275 350);
DISPLAY 0.808511 (-1275 350);
PAINT YELLOW (-1275 350);
FORCENOTE
PU
(-1275 175) 0;
DISPLAY LEFT (-1275 175);
DISPLAY 0.808511 (-1275 175);
PAINT YELLOW (-1275 175);
FORCENOTE
FUNCTION:SKIP RTC CLOCK
(-2560 1669) 0;
DISPLAY LEFT (-2560 1669);
DISPLAY 1.276596 (-2560 1669);
PAINT YELLOW (-2560 1669);
FORCENOTE
PCH INTERNAL: 20K PULL DOWN
(-2560 1469) 0;
DISPLAY LEFT (-2560 1469);
DISPLAY 1.276596 (-2560 1469);
PAINT YELLOW (-2560 1469);
FORCENOTE
DEFAULT: 1 (NATIVE&GPI FUNCTION ARE ENABLED)
(-5710 1569) 0;
DISPLAY LEFT (-5710 1569);
DISPLAY 1.276596 (-5710 1569);
PAINT YELLOW (-5710 1569);
FORCENOTE
FUNCTION:VISA DEFAULT
(-5710 1669) 0;
DISPLAY LEFT (-5710 1669);
DISPLAY 1.276596 (-5710 1669);
PAINT YELLOW (-5710 1669);
FORCENOTE
GROUP: GPPC_H_0
(-5710 1769) 0;
DISPLAY LEFT (-5710 1769);
DISPLAY 1.276596 (-5710 1769);
PAINT YELLOW (-5710 1769);
FORCENOTE
DEFAULT: 0 (MASTER ATTACHED FLASH)
(-8835 3569) 0;
DISPLAY LEFT (-8835 3569);
DISPLAY 1.276596 (-8835 3569);
PAINT YELLOW (-8835 3569);
FORCENOTE
PCH INTERNAL: PULL DOWN
(-8835 1469) 0;
DISPLAY LEFT (-8835 1469);
DISPLAY 1.276596 (-8835 1469);
PAINT YELLOW (-8835 1469);
FORCENOTE
GROUP: GPP_I_23
(-2560 -306) 0;
DISPLAY LEFT (-2560 -306);
DISPLAY 1.276596 (-2560 -306);
PAINT YELLOW (-2560 -306);
FORCENOTE
FUNCTION:RSVD (PCH TEST MODE)
(-2560 -406) 0;
DISPLAY LEFT (-2560 -406);
DISPLAY 1.276596 (-2560 -406);
PAINT YELLOW (-2560 -406);
FORCENOTE
DEFAULT: 0 
(-2560 -506) 0;
DISPLAY LEFT (-2560 -506);
DISPLAY 1.276596 (-2560 -506);
PAINT YELLOW (-2560 -506);
FORCENOTE
PCH INTERNAL: 20KOHM PULL DOWN
(-2560 -606) 0;
DISPLAY LEFT (-2560 -606);
DISPLAY 1.276596 (-2560 -606);
PAINT YELLOW (-2560 -606);
FORCENOTE
FOLLOW ARCHER CITY DESIGN TO RESERVE
(-2560 -706) 0;
DISPLAY LEFT (-2560 -706);
DISPLAY 1.276596 (-2560 -706);
PAINT YELLOW (-2560 -706);
QUIT
